# T6G (Grand Teton) — schematic netlist excerpt (pin names and nets, part order shuffled) for the footprints in the layout excerpt that follows; sources: Cadence DE-HDL packaged netlist, KiCad conversion of 04192023_DAF0TMB3IC0_F0TG_MB_C_brd_V02_OCP.brd

C6545  Q_CAP_DIFFBUS  DIFF BUS_0.22UF 6.3V 20% X6S  pkg C0201  page 286 : \1\ = P5E_CPU0_P1_TX_BUF_C_DP<6> ; \2\ = P5E_CPU0_P1_TX_BUF_DP<6>
C206  Q_CAP  0.1UF 10V 10% X7S  pkg C0201  page 334 : A = P1V8_CPU1_RT1_1A_1D ; B = GND
C409  Q_CAP  100UF 4V 20% X6S  pkg C0805  page 345 : A = P0V9_CPU1_RT2_2A ; B = GND

Q74  MOSFET_NCH_DUAL  PJT138K IC  pkg SOT363XD  page 127
  S1  = GND
  G1  = FM_SMB_2_ALERT_GPU_N
  D2  = FM_SMB_2_ALERT_GPU_ISO_N
  S2  = GND
  G2  = FM_SMB_2_ALERT_GPU
  D1  = FM_SMB_2_ALERT_GPU

(kicad_pcb
	(version 20260206)
	(generator "pcbnew")
	(generator_version "10.0")
	(general
		(thickness 1.6)
		(legacy_teardrops no)
	)
	(paper "A4")
	(title_block
		(title "04192023_DAF0TMB3IC0_F0TG_MB_C_brd_V02_OCP.brd")
		(comment 1 "Grand Teton / footprints 6236-6239 of 8354")
	)
	(layers
		(0 "F.Cu" signal "TOP")
		(4 "In1.Cu" signal "GND")
		(6 "In2.Cu" signal "IN1")
		(8 "In3.Cu" signal "GND1")
		(10 "In4.Cu" signal "IN2")
		(12 "In5.Cu" signal "GND2")
		(14 "In6.Cu" signal "IN3")
		(16 "In7.Cu" signal "GND3")
		(18 "In8.Cu" signal "VCC")
		(20 "In9.Cu" signal "VCC1")
		(22 "In10.Cu" signal "GND4")
		(24 "In11.Cu" signal "IN4")
		(26 "In12.Cu" signal "GND5")
		(28 "In13.Cu" signal "IN5")
		(30 "In14.Cu" signal "GND6")
		(32 "In15.Cu" signal "IN6")
		(34 "In16.Cu" signal "GND7")
		(2 "B.Cu" signal "BOTTOM")
		(9 "F.Adhes" user "F.Adhesive")
		(11 "B.Adhes" user "B.Adhesive")
		(13 "F.Paste" user "Package Geometry/Pastemask Top")
		(15 "B.Paste" user "Package Geometry/Pastemask Bottom")
		(5 "F.SilkS" user "Ref Des/Silkscreen Top")
		(7 "B.SilkS" user "Ref Des/Silkscreen Bottom")
		(1 "F.Mask" user "Board Geometry/Soldermask Top")
		(3 "B.Mask" user "Board Geometry/Soldermask Bottom")
		(17 "Dwgs.User" user "User.Drawings")
		(19 "Cmts.User" user "User.Comments")
		(21 "Eco1.User" user "User.Eco1")
		(23 "Eco2.User" user "User.Eco2")
		(25 "Edge.Cuts" user "Board Geometry/Outline")
		(27 "Margin" user)
		(31 "F.CrtYd" user "Package Geometry/Place Bound Top")
		(29 "B.CrtYd" user "Package Geometry/Place Bound Bottom")
		(35 "F.Fab" user "Ref Des/Assembly Top")
		(33 "B.Fab" user "Ref Des/Assembly Bottom")
	)
	(footprint ""
		(layer "B.Cu")
		(at 142.04061 -388.846568)
		(property "Reference" "C409"
			(at 0 0 0)
			(layer "B.SilkS")
			(hide yes)
			(effects
				(font
					(size 1.27 1.27)
				)
				(justify mirror)
			)
		)
		(property "Value" ""
			(at 0 0 0)
			(layer "B.Fab")
			(effects
				(font
					(size 1.27 1.27)
				)
				(justify mirror)
			)
		)
		(duplicate_pad_numbers_are_jumpers no)
		(fp_line
			(start -1.524 -0.762)
			(end -1.524 0.762)
			(stroke
				(width 0.1524)
				(type default)
			)
			(layer "B.SilkS")
		)
		(fp_line
			(start -1.524 0.762)
			(end 1.524 0.762)
			(stroke
				(width 0.1524)
				(type default)
			)
			(layer "B.SilkS")
		)
		(fp_line
			(start 1.524 -0.762)
			(end -1.524 -0.762)
			(stroke
				(width 0.1524)
				(type default)
			)
			(layer "B.SilkS")
		)
		(fp_line
			(start 1.524 0.762)
			(end 1.524 -0.762)
			(stroke
				(width 0.1524)
				(type default)
			)
			(layer "B.SilkS")
		)
		(fp_line
			(start -1.1049 -0.724916)
			(end 1.1049 -0.724916)
			(stroke
				(width 0.1)
				(type default)
			)
			(layer "B.Fab")
		)
		(fp_line
			(start -1.1049 0.724916)
			(end -1.1049 -0.724916)
			(stroke
				(width 0.1)
				(type default)
			)
			(layer "B.Fab")
		)
		(fp_line
			(start 1.1049 -0.724916)
			(end 1.1049 0.724916)
			(stroke
				(width 0.1)
				(type default)
			)
			(layer "B.Fab")
		)
		(fp_line
			(start 1.1049 0.724916)
			(end -1.1049 0.724916)
			(stroke
				(width 0.1)
				(type default)
			)
			(layer "B.Fab")
		)
		(pad "1" smd rect
			(at 0.889 0)
			(size 1.016 1.27)
			(layers "B.Cu" "B.Mask" "B.Paste")
			(net "P0V9_CPU1_RT2_2A")
		)
		(pad "2" smd rect
			(at -0.889 0)
			(size 1.016 1.27)
			(layers "B.Cu" "B.Mask" "B.Paste")
			(net "GND")
		)
	)
	(footprint ""
		(layer "B.Cu")
		(at 106.68 -417.322 90)
		(property "Reference" "Q74"
			(at -3.683 -0.28067 270)
			(unlocked yes)
			(layer "B.SilkS")
			(effects
				(font
					(size 0.7874 0.5842)
					(thickness 0.1524)
				)
				(justify left mirror)
			)
		)
		(property "Value" ""
			(at 0 0 90)
			(layer "B.Fab")
			(effects
				(font
					(size 1.27 1.27)
				)
				(justify mirror)
			)
		)
		(duplicate_pad_numbers_are_jumpers no)
		(fp_line
			(start 1.332738 -1.100074)
			(end 0.4826 -1.100074)
			(stroke
				(width 0.1524)
				(type default)
			)
			(layer "B.SilkS")
		)
		(fp_line
			(start 0.4826 -1.100074)
			(end 0 -0.541274)
			(stroke
				(width 0.1524)
				(type default)
			)
			(layer "B.SilkS")
		)
		(fp_line
			(start -0.4826 -1.100074)
			(end -1.332738 -1.100074)
			(stroke
				(width 0.1524)
				(type default)
			)
			(layer "B.SilkS")
		)
		(fp_line
			(start -1.332738 -1.100074)
			(end -1.332738 1.100074)
			(stroke
				(width 0.1524)
				(type default)
			)
			(layer "B.SilkS")
		)
		(fp_line
			(start 0 -0.541274)
			(end -0.4826 -1.100074)
			(stroke
				(width 0.1524)
				(type default)
			)
			(layer "B.SilkS")
		)
		(fp_line
			(start 1.332738 1.100074)
			(end 1.332738 -1.100074)
			(stroke
				(width 0.1524)
				(type default)
			)
			(layer "B.SilkS")
		)
		(fp_line
			(start -1.332738 1.100074)
			(end 1.332738 1.100074)
			(stroke
				(width 0.1524)
				(type default)
			)
			(layer "B.SilkS")
		)
		(fp_poly
			(pts
				(xy 1.441196 -0.658876) (xy 2.143252 -0.307848) (xy 2.143252 -1.009904)
			)
			(stroke
				(width 0)
				(type default)
			)
			(fill yes)
			(layer "B.SilkS")
		)
		(fp_line
			(start 0.674878 -1.100074)
			(end -0.674878 -1.100074)
			(stroke
				(width 0.1)
				(type default)
			)
			(layer "B.Fab")
		)
		(fp_line
			(start -0.674878 -1.100074)
			(end -0.674878 1.100074)
			(stroke
				(width 0.1)
				(type default)
			)
			(layer "B.Fab")
		)
		(fp_line
			(start 0.674878 1.100074)
			(end 0.674878 -1.100074)
			(stroke
				(width 0.1)
				(type default)
			)
			(layer "B.Fab")
		)
		(fp_line
			(start -0.674878 1.100074)
			(end 0.674878 1.100074)
			(stroke
				(width 0.1)
				(type default)
			)
			(layer "B.Fab")
		)
		(fp_poly
			(pts
				(xy 2.2352 -0.298958) (xy 2.2352 -1.001014) (xy 1.533144 -0.649986)
			)
			(stroke
				(width 0)
				(type default)
			)
			(fill yes)
			(layer "B.Fab")
		)
		(pad "1" smd rect
			(at 0.94996 -0.649986 180)
			(size 0.4318 0.508)
			(layers "B.Cu" "B.Mask" "B.Paste")
			(net "GND")
		)
		(pad "2" smd rect
			(at 0.94996 0 180)
			(size 0.4318 0.508)
			(layers "B.Cu" "B.Mask" "B.Paste")
			(net "FM_SMB_2_ALERT_GPU_N")
		)
		(pad "3" smd rect
			(at 0.94996 0.649986 180)
			(size 0.4318 0.508)
			(layers "B.Cu" "B.Mask" "B.Paste")
			(net "FM_SMB_2_ALERT_GPU_ISO_N")
		)
		(pad "4" smd rect
			(at -0.94996 0.649986 180)
			(size 0.4318 0.508)
			(layers "B.Cu" "B.Mask" "B.Paste")
			(net "GND")
		)
		(pad "5" smd rect
			(at -0.94996 0 180)
			(size 0.4318 0.508)
			(layers "B.Cu" "B.Mask" "B.Paste")
			(net "FM_SMB_2_ALERT_GPU")
		)
		(pad "6" smd rect
			(at -0.94996 -0.649986 180)
			(size 0.4318 0.508)
			(layers "B.Cu" "B.Mask" "B.Paste")
			(net "FM_SMB_2_ALERT_GPU")
		)
	)
	(footprint ""
		(layer "B.Cu")
		(at 90.846148 -388.011162 -90)
		(property "Reference" "C206"
			(at 0 0 90)
			(layer "B.SilkS")
			(hide yes)
			(effects
				(font
					(size 1.27 1.27)
				)
				(justify mirror)
			)
		)
		(property "Value" ""
			(at 0 0 90)
			(layer "B.Fab")
			(effects
				(font
					(size 1.27 1.27)
				)
				(justify mirror)
			)
		)
		(duplicate_pad_numbers_are_jumpers no)
		(fp_line
			(start -0.299974 0.150114)
			(end 0.299974 0.150114)
			(stroke
				(width 0.1)
				(type default)
			)
			(layer "B.Fab")
		)
		(fp_line
			(start 0.299974 0.150114)
			(end 0.299974 -0.150114)
			(stroke
				(width 0.1)
				(type default)
			)
			(layer "B.Fab")
		)
		(fp_line
			(start -0.299974 -0.150114)
			(end -0.299974 0.150114)
			(stroke
				(width 0.1)
				(type default)
			)
			(layer "B.Fab")
		)
		(fp_line
			(start 0.299974 -0.150114)
			(end -0.299974 -0.150114)
			(stroke
				(width 0.1)
				(type default)
			)
			(layer "B.Fab")
		)
		(pad "1" smd rect
			(at 0.2667 0 90)
			(size 0.3048 0.381)
			(layers "B.Cu" "B.Mask" "B.Paste")
			(net "P1V8_CPU1_RT1_1A_1D")
		)
		(pad "2" smd rect
			(at -0.2667 0 90)
			(size 0.3048 0.381)
			(layers "B.Cu" "B.Mask" "B.Paste")
			(net "GND")
		)
	)
	(footprint ""
		(layer "B.Cu")
		(at 324.593966 -416.899344 90)
		(property "Reference" "C6545"
			(at 0 0 90)
			(layer "B.SilkS")
			(hide yes)
			(effects
				(font
					(size 1.27 1.27)
				)
				(justify mirror)
			)
		)
		(property "Value" ""
			(at 0 0 90)
			(layer "B.Fab")
			(effects
				(font
					(size 1.27 1.27)
				)
				(justify mirror)
			)
		)
		(duplicate_pad_numbers_are_jumpers no)
		(fp_line
			(start 0.299974 -0.150114)
			(end -0.299974 -0.150114)
			(stroke
				(width 0.1)
				(type default)
			)
			(layer "B.Fab")
		)
		(fp_line
			(start -0.299974 -0.150114)
			(end -0.299974 0.150114)
			(stroke
				(width 0.1)
				(type default)
			)
			(layer "B.Fab")
		)
		(fp_line
			(start 0.299974 0.150114)
			(end 0.299974 -0.150114)
			(stroke
				(width 0.1)
				(type default)
			)
			(layer "B.Fab")
		)
		(fp_line
			(start -0.299974 0.150114)
			(end 0.299974 0.150114)
			(stroke
				(width 0.1)
				(type default)
			)
			(layer "B.Fab")
		)
		(pad "1" smd rect
			(at 0.2667 0 270)
			(size 0.3048 0.381)
			(layers "B.Cu" "B.Mask" "B.Paste")
			(net "P5E_CPU0_P1_TX_BUF_C_DP<6>")
		)
		(pad "2" smd rect
			(at -0.2667 0 270)
			(size 0.3048 0.381)
			(layers "B.Cu" "B.Mask" "B.Paste")
			(net "P5E_CPU0_P1_TX_BUF_DP<6>")
		)
	)
)
